# T6G (Grand Teton) — schematic netlist excerpt (pin names and nets, part order shuffled) for the footprints in the layout excerpt that follows; sources: Cadence DE-HDL packaged netlist, KiCad conversion of 04192023_DAF0TMB3IC0_F0TG_MB_C_brd_V02_OCP.brd

R3167  Q_RES  4.7K 1% CHIP  pkg 0402LF  page 137 : A = OCP_V3_2_ID1 ; B = GND
PC267_2  Q_CAP  22UF 16V 20% X6S  pkg C0805  page 211 : A = SW_P12V_AUX_PVDDCR_CPU0_P1_FLT ; B = GND
PC138_5  Q_CAP  22UF 16V 20% X6S  pkg C0805  page 203 : A = SW_P12V_AUX_PVDDCR_CPU1_P0_FLT ; B = GND

(kicad_pcb
	(version 20260206)
	(generator "pcbnew")
	(generator_version "10.0")
	(general
		(thickness 1.6)
		(legacy_teardrops no)
	)
	(paper "A4")
	(title_block
		(title "04192023_DAF0TMB3IC0_F0TG_MB_C_brd_V02_OCP.brd")
		(comment 1 "Grand Teton / footprints 5233-5235 of 8354")
	)
	(layers
		(0 "F.Cu" signal "TOP")
		(4 "In1.Cu" signal "GND")
		(6 "In2.Cu" signal "IN1")
		(8 "In3.Cu" signal "GND1")
		(10 "In4.Cu" signal "IN2")
		(12 "In5.Cu" signal "GND2")
		(14 "In6.Cu" signal "IN3")
		(16 "In7.Cu" signal "GND3")
		(18 "In8.Cu" signal "VCC")
		(20 "In9.Cu" signal "VCC1")
		(22 "In10.Cu" signal "GND4")
		(24 "In11.Cu" signal "IN4")
		(26 "In12.Cu" signal "GND5")
		(28 "In13.Cu" signal "IN5")
		(30 "In14.Cu" signal "GND6")
		(32 "In15.Cu" signal "IN6")
		(34 "In16.Cu" signal "GND7")
		(2 "B.Cu" signal "BOTTOM")
		(9 "F.Adhes" user "F.Adhesive")
		(11 "B.Adhes" user "B.Adhesive")
		(13 "F.Paste" user "Package Geometry/Pastemask Top")
		(15 "B.Paste" user "Package Geometry/Pastemask Bottom")
		(5 "F.SilkS" user "Ref Des/Silkscreen Top")
		(7 "B.SilkS" user "Ref Des/Silkscreen Bottom")
		(1 "F.Mask" user "Board Geometry/Soldermask Top")
		(3 "B.Mask" user "Board Geometry/Soldermask Bottom")
		(17 "Dwgs.User" user "User.Drawings")
		(19 "Cmts.User" user "User.Comments")
		(21 "Eco1.User" user "User.Eco1")
		(23 "Eco2.User" user "User.Eco2")
		(25 "Edge.Cuts" user "Board Geometry/Outline")
		(27 "Margin" user)
		(31 "F.CrtYd" user "Package Geometry/Place Bound Top")
		(29 "B.CrtYd" user "Package Geometry/Place Bound Bottom")
		(35 "F.Fab" user "Ref Des/Assembly Top")
		(33 "B.Fab" user "Ref Des/Assembly Bottom")
	)
	(footprint ""
		(layer "B.Cu")
		(at 74.55408 -4.251198 90)
		(property "Reference" "R3167"
			(at 0 0 90)
			(layer "B.SilkS")
			(hide yes)
			(effects
				(font
					(size 1.27 1.27)
				)
				(justify mirror)
			)
		)
		(property "Value" ""
			(at 0 0 90)
			(layer "B.Fab")
			(effects
				(font
					(size 1.27 1.27)
				)
				(justify mirror)
			)
		)
		(duplicate_pad_numbers_are_jumpers no)
		(fp_line
			(start 0.7874 -0.4064)
			(end -0.7874 -0.4064)
			(stroke
				(width 0.1524)
				(type default)
			)
			(layer "B.SilkS")
		)
		(fp_line
			(start -0.7874 -0.4064)
			(end -0.7874 0.4064)
			(stroke
				(width 0.1524)
				(type default)
			)
			(layer "B.SilkS")
		)
		(fp_line
			(start 0.7874 0.4064)
			(end 0.7874 -0.4064)
			(stroke
				(width 0.1524)
				(type default)
			)
			(layer "B.SilkS")
		)
		(fp_line
			(start -0.7874 0.4064)
			(end 0.7874 0.4064)
			(stroke
				(width 0.1524)
				(type default)
			)
			(layer "B.SilkS")
		)
		(fp_line
			(start 0.67945 -0.305054)
			(end 0.12065 -0.305054)
			(stroke
				(width 0.1)
				(type default)
			)
			(layer "B.Fab")
		)
		(fp_line
			(start 0.12065 -0.305054)
			(end 0.12065 -0.2794)
			(stroke
				(width 0.1)
				(type default)
			)
			(layer "B.Fab")
		)
		(fp_line
			(start -0.12065 -0.3048)
			(end -0.67945 -0.3048)
			(stroke
				(width 0.1)
				(type default)
			)
			(layer "B.Fab")
		)
		(fp_line
			(start -0.67945 -0.3048)
			(end -0.67945 0.3048)
			(stroke
				(width 0.1)
				(type default)
			)
			(layer "B.Fab")
		)
		(fp_line
			(start 0.12065 -0.2794)
			(end -0.12065 -0.2794)
			(stroke
				(width 0.1)
				(type default)
			)
			(layer "B.Fab")
		)
		(fp_line
			(start -0.12065 -0.2794)
			(end -0.12065 -0.3048)
			(stroke
				(width 0.1)
				(type default)
			)
			(layer "B.Fab")
		)
		(fp_line
			(start 0.12065 0.2794)
			(end 0.12065 0.3048)
			(stroke
				(width 0.1)
				(type default)
			)
			(layer "B.Fab")
		)
		(fp_line
			(start -0.120396 0.2794)
			(end 0.12065 0.2794)
			(stroke
				(width 0.1)
				(type default)
			)
			(layer "B.Fab")
		)
		(fp_line
			(start 0.67945 0.3048)
			(end 0.67945 -0.305054)
			(stroke
				(width 0.1)
				(type default)
			)
			(layer "B.Fab")
		)
		(fp_line
			(start 0.12065 0.3048)
			(end 0.67945 0.3048)
			(stroke
				(width 0.1)
				(type default)
			)
			(layer "B.Fab")
		)
		(fp_line
			(start -0.120396 0.3048)
			(end -0.120396 0.2794)
			(stroke
				(width 0.1)
				(type default)
			)
			(layer "B.Fab")
		)
		(fp_line
			(start -0.67945 0.3048)
			(end -0.120396 0.3048)
			(stroke
				(width 0.1)
				(type default)
			)
			(layer "B.Fab")
		)
		(pad "1" smd circle
			(at 0.40005 0 270)
			(size 0 0)
			(layers "B.Cu" "B.Mask" "B.Paste")
			(net "OCP_V3_2_ID1")
		)
		(pad "2" smd circle
			(at -0.40005 0 270)
			(size 0 0)
			(layers "B.Cu" "B.Mask" "B.Paste")
			(net "GND")
		)
	)
	(footprint ""
		(layer "B.Cu")
		(at 89.560146 -178.736244 90)
		(property "Reference" "PC267_2"
			(at 0 0 90)
			(layer "B.SilkS")
			(hide yes)
			(effects
				(font
					(size 1.27 1.27)
				)
				(justify mirror)
			)
		)
		(property "Value" ""
			(at 0 0 90)
			(layer "B.Fab")
			(effects
				(font
					(size 1.27 1.27)
				)
				(justify mirror)
			)
		)
		(duplicate_pad_numbers_are_jumpers no)
		(fp_line
			(start 1.524 -0.762)
			(end -1.524 -0.762)
			(stroke
				(width 0.1524)
				(type default)
			)
			(layer "B.SilkS")
		)
		(fp_line
			(start -1.524 -0.762)
			(end -1.524 0.762)
			(stroke
				(width 0.1524)
				(type default)
			)
			(layer "B.SilkS")
		)
		(fp_line
			(start 1.524 0.762)
			(end 1.524 -0.762)
			(stroke
				(width 0.1524)
				(type default)
			)
			(layer "B.SilkS")
		)
		(fp_line
			(start -1.524 0.762)
			(end 1.524 0.762)
			(stroke
				(width 0.1524)
				(type default)
			)
			(layer "B.SilkS")
		)
		(fp_line
			(start 1.1049 -0.724916)
			(end 1.1049 0.724916)
			(stroke
				(width 0.1)
				(type default)
			)
			(layer "B.Fab")
		)
		(fp_line
			(start -1.1049 -0.724916)
			(end 1.1049 -0.724916)
			(stroke
				(width 0.1)
				(type default)
			)
			(layer "B.Fab")
		)
		(fp_line
			(start 1.1049 0.724916)
			(end -1.1049 0.724916)
			(stroke
				(width 0.1)
				(type default)
			)
			(layer "B.Fab")
		)
		(fp_line
			(start -1.1049 0.724916)
			(end -1.1049 -0.724916)
			(stroke
				(width 0.1)
				(type default)
			)
			(layer "B.Fab")
		)
		(pad "1" smd rect
			(at 0.889 0 90)
			(size 1.016 1.27)
			(layers "B.Cu" "B.Mask" "B.Paste")
			(net "SW_P12V_AUX_PVDDCR_CPU0_P1_FLT")
		)
		(pad "2" smd rect
			(at -0.889 0 90)
			(size 1.016 1.27)
			(layers "B.Cu" "B.Mask" "B.Paste")
			(net "GND")
		)
	)
	(footprint ""
		(layer "B.Cu")
		(at 344.511884 -335.092294 90)
		(property "Reference" "PC138_5"
			(at 0 0 90)
			(layer "B.SilkS")
			(hide yes)
			(effects
				(font
					(size 1.27 1.27)
				)
				(justify mirror)
			)
		)
		(property "Value" ""
			(at 0 0 90)
			(layer "B.Fab")
			(effects
				(font
					(size 1.27 1.27)
				)
				(justify mirror)
			)
		)
		(duplicate_pad_numbers_are_jumpers no)
		(fp_line
			(start 1.524 -0.762)
			(end -1.524 -0.762)
			(stroke
				(width 0.1524)
				(type default)
			)
			(layer "B.SilkS")
		)
		(fp_line
			(start -1.524 -0.762)
			(end -1.524 0.762)
			(stroke
				(width 0.1524)
				(type default)
			)
			(layer "B.SilkS")
		)
		(fp_line
			(start 1.524 0.762)
			(end 1.524 -0.762)
			(stroke
				(width 0.1524)
				(type default)
			)
			(layer "B.SilkS")
		)
		(fp_line
			(start -1.524 0.762)
			(end 1.524 0.762)
			(stroke
				(width 0.1524)
				(type default)
			)
			(layer "B.SilkS")
		)
		(fp_line
			(start 1.1049 -0.724916)
			(end 1.1049 0.724916)
			(stroke
				(width 0.1)
				(type default)
			)
			(layer "B.Fab")
		)
		(fp_line
			(start -1.1049 -0.724916)
			(end 1.1049 -0.724916)
			(stroke
				(width 0.1)
				(type default)
			)
			(layer "B.Fab")
		)
		(fp_line
			(start 1.1049 0.724916)
			(end -1.1049 0.724916)
			(stroke
				(width 0.1)
				(type default)
			)
			(layer "B.Fab")
		)
		(fp_line
			(start -1.1049 0.724916)
			(end -1.1049 -0.724916)
			(stroke
				(width 0.1)
				(type default)
			)
			(layer "B.Fab")
		)
		(pad "1" smd rect
			(at 0.889 0 90)
			(size 1.016 1.27)
			(layers "B.Cu" "B.Mask" "B.Paste")
			(net "SW_P12V_AUX_PVDDCR_CPU1_P0_FLT")
		)
		(pad "2" smd rect
			(at -0.889 0 90)
			(size 1.016 1.27)
			(layers "B.Cu" "B.Mask" "B.Paste")
			(net "GND")
		)
	)
)
